(kicad_pcb
	(version 20241229)
	(generator "pcbnew")
	(generator_version "9.0")
	(general
		(thickness 1.294)
		(legacy_teardrops no)
	)
	(paper "A3")
	(title_block
		(title "Kintex 410T devboard")
		(date "2024-04-03")
		(rev "1.1.2")
		(comment 9 "footprints 946-950 of 975")
	)
	(layers
		(0 "F.Cu" mixed)
		(4 "In1.Cu" power)
		(6 "In2.Cu" power)
		(8 "In3.Cu" mixed)
		(10 "In4.Cu" power)
		(12 "In5.Cu" mixed)
		(14 "In6.Cu" power)
		(16 "In7.Cu" mixed)
		(18 "In8.Cu" power)
		(2 "B.Cu" mixed)
		(9 "F.Adhes" user "F.Adhesive")
		(11 "B.Adhes" user "B.Adhesive")
		(13 "F.Paste" user)
		(15 "B.Paste" user)
		(5 "F.SilkS" user "F.Silkscreen")
		(7 "B.SilkS" user "B.Silkscreen")
		(1 "F.Mask" user)
		(3 "B.Mask" user)
		(17 "Dwgs.User" user "User.Drawings")
		(19 "Cmts.User" user "User.Comments")
		(21 "Eco1.User" user "User.Eco1")
		(23 "Eco2.User" user "User.Eco2")
		(25 "Edge.Cuts" user)
		(27 "Margin" user)
		(31 "F.CrtYd" user "F.Courtyard")
		(29 "B.CrtYd" user "B.Courtyard")
		(35 "F.Fab" user)
		(33 "B.Fab" user)
	)
	(footprint "antmicro-footprints:R_0402_1005Metric"
		(layer "B.Cu")
		(at 266.8 79.4 -90)
		(descr "Resistor SMD 0402")
		(tags "resistor SMD 0402")
		(property "Reference" "R140"
			(at -1.4 -1.25 90)
			(layer "B.SilkS")
			(effects
				(font
					(size 0.7 0.7)
					(thickness 0.15)
				)
				(justify left bottom mirror)
			)
		)
		(property "Value" "R_10k_0402"
			(at 0 -1.4 90)
			(layer "B.Fab")
			(effects
				(font
					(size 0.7 0.7)
					(thickness 0.15)
				)
				(justify left bottom mirror)
			)
		)
		(property "Description" "SMD Chip Resistor, 10 kohm, ± 1%, 62.5 mW, 0402 [1005 Metric], Thick Film, General Purpose"
			(at 0 0 270)
			(layer "F.Fab")
			(hide yes)
			(effects
				(font
					(size 1.27 1.27)
					(thickness 0.15)
				)
			)
		)
		(property "Author" "Antmicro"
			(at 187.4 346.2 0)
			(layer "B.Fab")
			(hide yes)
			(effects
				(font
					(size 1 1)
					(thickness 0.15)
				)
				(justify mirror)
			)
		)
		(property "License" "Apache-2.0"
			(at 187.4 346.2 0)
			(layer "B.Fab")
			(hide yes)
			(effects
				(font
					(size 1 1)
					(thickness 0.15)
				)
				(justify mirror)
			)
		)
		(property "MPN" "CR0402-FX-1002GLF"
			(at 187.4 346.2 0)
			(layer "B.Fab")
			(hide yes)
			(effects
				(font
					(size 1 1)
					(thickness 0.15)
				)
				(justify mirror)
			)
		)
		(property "Manufacturer" "Bourns"
			(at 187.4 346.2 0)
			(layer "B.Fab")
			(hide yes)
			(effects
				(font
					(size 1 1)
					(thickness 0.15)
				)
				(justify mirror)
			)
		)
		(property "Tolerance" "1%"
			(at 187.4 346.2 0)
			(layer "B.Fab")
			(hide yes)
			(effects
				(font
					(size 1 1)
					(thickness 0.15)
				)
				(justify mirror)
			)
		)
		(property "Val" "10k"
			(at 187.4 346.2 0)
			(layer "B.Fab")
			(hide yes)
			(effects
				(font
					(size 1 1)
					(thickness 0.15)
				)
				(justify mirror)
			)
		)
		(sheetname "User GPIO + LED + button + DIP switch")
		(sheetfile "user-gpio.kicad_sch")
		(attr smd)
		(fp_rect
			(start -0.925 0.47)
			(end 0.925 -0.47)
			(stroke
				(width 0.05)
				(type default)
			)
			(fill no)
			(layer "B.CrtYd")
		)
		(fp_rect
			(start -0.5 0.25)
			(end 0.5 -0.25)
			(stroke
				(width 0.15)
				(type solid)
			)
			(fill no)
			(layer "B.Fab")
		)
		(pad "1" smd roundrect
			(at -0.48 0 270)
			(size 0.59 0.64)
			(layers "B.Cu" "B.Mask" "B.Paste")
			(roundrect_rratio 0.25)
			(net 26 "+1V8")
			(pintype "passive")
		)
		(pad "2" smd roundrect
			(at 0.48 0 270)
			(size 0.59 0.64)
			(layers "B.Cu" "B.Mask" "B.Paste")
			(roundrect_rratio 0.25)
			(net 1228 "/USER_IO.BUTTON0")
			(pintype "passive")
		)
	)
	(footprint "antmicro-footprints:C_0402_1005Metric"
		(layer "B.Cu")
		(at 229.2 165.4 90)
		(descr "Capacitor SMD 0402")
		(tags "capacitor SMD 0402")
		(property "Reference" "C193"
			(at 3.675 0.375 270)
			(layer "B.SilkS")
			(effects
				(font
					(size 0.7 0.7)
					(thickness 0.15)
				)
				(justify left bottom mirror)
			)
		)
		(property "Value" "C_1u_0402"
			(at 0 -1.4 270)
			(layer "B.Fab")
			(effects
				(font
					(size 0.7 0.7)
					(thickness 0.15)
				)
				(justify left bottom mirror)
			)
		)
		(property "Description" "SMD Multilayer Ceramic Capacitor, 1 µF, 10 V, 0402 [1005 Metric], ± 10%, X6S, C"
			(at 0 0 90)
			(layer "F.Fab")
			(hide yes)
			(effects
				(font
					(size 1.27 1.27)
					(thickness 0.15)
				)
			)
		)
		(property "Author" "Antmicro"
			(at 394.6 -63.8 0)
			(layer "B.Fab")
			(hide yes)
			(effects
				(font
					(size 1 1)
					(thickness 0.15)
				)
				(justify mirror)
			)
		)
		(property "Dielectric" ""
			(at 394.6 -63.8 0)
			(layer "B.Fab")
			(hide yes)
			(effects
				(font
					(size 1 1)
					(thickness 0.15)
				)
				(justify mirror)
			)
		)
		(property "License" "Apache-2.0"
			(at 394.6 -63.8 0)
			(layer "B.Fab")
			(hide yes)
			(effects
				(font
					(size 1 1)
					(thickness 0.15)
				)
				(justify mirror)
			)
		)
		(property "MPN" "C1005X6S1A105K050BC"
			(at 394.6 -63.8 0)
			(layer "B.Fab")
			(hide yes)
			(effects
				(font
					(size 1 1)
					(thickness 0.15)
				)
				(justify mirror)
			)
		)
		(property "Manufacturer" "TDK"
			(at 394.6 -63.8 0)
			(layer "B.Fab")
			(hide yes)
			(effects
				(font
					(size 1 1)
					(thickness 0.15)
				)
				(justify mirror)
			)
		)
		(property "Val" "1u"
			(at 394.6 -63.8 0)
			(layer "B.Fab")
			(hide yes)
			(effects
				(font
					(size 1 1)
					(thickness 0.15)
				)
				(justify mirror)
			)
		)
		(property "Voltage" ""
			(at 394.6 -63.8 0)
			(layer "B.Fab")
			(hide yes)
			(effects
				(font
					(size 1 1)
					(thickness 0.15)
				)
				(justify mirror)
			)
		)
		(sheetname "Power supply")
		(sheetfile "power-supply.kicad_sch")
		(attr smd)
		(fp_rect
			(start -0.925 0.47)
			(end 0.925 -0.47)
			(stroke
				(width 0.05)
				(type default)
			)
			(fill no)
			(layer "B.CrtYd")
		)
		(fp_line
			(start 0.504 -0.248)
			(end -0.494 -0.248)
			(stroke
				(width 0.15)
				(type solid)
			)
			(layer "B.Fab")
		)
		(fp_line
			(start -0.494 -0.248)
			(end -0.494 0.25)
			(stroke
				(width 0.15)
				(type solid)
			)
			(layer "B.Fab")
		)
		(fp_line
			(start 0.504 0.25)
			(end 0.504 -0.248)
			(stroke
				(width 0.15)
				(type solid)
			)
			(layer "B.Fab")
		)
		(fp_line
			(start -0.494 0.25)
			(end 0.504 0.25)
			(stroke
				(width 0.15)
				(type solid)
			)
			(layer "B.Fab")
		)
		(pad "1" smd roundrect
			(at -0.48 0 90)
			(size 0.59 0.64)
			(layers "B.Cu" "B.Mask" "B.Paste")
			(roundrect_rratio 0.25)
			(net 267 "/Power supply/VREG_2V7")
			(pintype "passive")
		)
		(pad "2" smd roundrect
			(at 0.48 0 90)
			(size 0.59 0.64)
			(layers "B.Cu" "B.Mask" "B.Paste")
			(roundrect_rratio 0.25)
			(net 1 "GND")
			(pintype "passive")
		)
	)
	(footprint "antmicro-footprints:R_0402_1005Metric"
		(layer "B.Cu")
		(at 224.2 146.2 -90)
		(descr "Resistor SMD 0402")
		(tags "resistor SMD 0402")
		(property "Reference" "R237"
			(at -3.625 -0.375 90)
			(layer "B.SilkS")
			(effects
				(font
					(size 0.7 0.7)
					(thickness 0.15)
				)
				(justify left bottom mirror)
			)
		)
		(property "Value" "R_10R_0402"
			(at 0 -1.4 90)
			(layer "B.Fab")
			(effects
				(font
					(size 0.7 0.7)
					(thickness 0.15)
				)
				(justify left bottom mirror)
			)
		)
		(property "Description" "SMD Chip Resistor, 10 ohm, ± 1%, 62.5 mW, 0402 [1005 Metric], Thick Film, General Purpose"
			(at 0 0 270)
			(layer "F.Fab")
			(hide yes)
			(effects
				(font
					(size 1.27 1.27)
					(thickness 0.15)
				)
			)
		)
		(property "Author" "Antmicro"
			(at 78 370.4 0)
			(layer "B.Fab")
			(hide yes)
			(effects
				(font
					(size 1 1)
					(thickness 0.15)
				)
				(justify mirror)
			)
		)
		(property "License" "Apache-2.0"
			(at 78 370.4 0)
			(layer "B.Fab")
			(hide yes)
			(effects
				(font
					(size 1 1)
					(thickness 0.15)
				)
				(justify mirror)
			)
		)
		(property "MPN" "CR0402-FX-10R0GLF"
			(at 78 370.4 0)
			(layer "B.Fab")
			(hide yes)
			(effects
				(font
					(size 1 1)
					(thickness 0.15)
				)
				(justify mirror)
			)
		)
		(property "Manufacturer" "Bourns"
			(at 78 370.4 0)
			(layer "B.Fab")
			(hide yes)
			(effects
				(font
					(size 1 1)
					(thickness 0.15)
				)
				(justify mirror)
			)
		)
		(property "Tolerance" "1%"
			(at 78 370.4 0)
			(layer "B.Fab")
			(hide yes)
			(effects
				(font
					(size 1 1)
					(thickness 0.15)
				)
				(justify mirror)
			)
		)
		(property "Val" "10R"
			(at 78 370.4 0)
			(layer "B.Fab")
			(hide yes)
			(effects
				(font
					(size 1 1)
					(thickness 0.15)
				)
				(justify mirror)
			)
		)
		(sheetname "HDMI + Ethernet")
		(sheetfile "hdmi-ethernet.kicad_sch")
		(attr smd)
		(fp_rect
			(start -0.925 0.47)
			(end 0.925 -0.47)
			(stroke
				(width 0.05)
				(type default)
			)
			(fill no)
			(layer "B.CrtYd")
		)
		(fp_rect
			(start -0.5 0.25)
			(end 0.5 -0.25)
			(stroke
				(width 0.15)
				(type solid)
			)
			(fill no)
			(layer "B.Fab")
		)
		(pad "1" smd roundrect
			(at -0.48 0 270)
			(size 0.59 0.64)
			(layers "B.Cu" "B.Mask" "B.Paste")
			(roundrect_rratio 0.25)
			(net 520 "/FPGA Bank 18 & 32/ETH_RMII.RXD1")
			(pintype "passive")
		)
		(pad "2" smd roundrect
			(at 0.48 0 270)
			(size 0.59 0.64)
			(layers "B.Cu" "B.Mask" "B.Paste")
			(roundrect_rratio 0.25)
			(net 945 "/HDMI + Ethernet/ETH_PHY_RXD1")
			(pintype "passive")
		)
	)
	(footprint "antmicro-footprints:C_0402_1005Metric"
		(layer "B.Cu")
		(at 196.325 125.825)
		(descr "Capacitor SMD 0402")
		(tags "capacitor SMD 0402")
		(property "Reference" "C116"
			(at 25.375 -29.325 180)
			(layer "B.SilkS")
			(effects
				(font
					(size 0.7 0.7)
					(thickness 0.15)
				)
				(justify left bottom mirror)
			)
		)
		(property "Value" "C_100n_0402"
			(at 0 -1.169 180)
			(layer "B.Fab")
			(effects
				(font
					(size 0.7 0.7)
					(thickness 0.15)
				)
				(justify left bottom mirror)
			)
		)
		(property "Description" "SMD Multilayer Ceramic Capacitor, 0.1 µF, 50 V, 0402 [1005 Metric], ± 10%, X5R, GRM Series"
			(at 0 0 0)
			(layer "F.Fab")
			(hide yes)
			(effects
				(font
					(size 1.27 1.27)
					(thickness 0.15)
				)
			)
		)
		(property "Author" "Antmicro"
			(at 0 0 0)
			(layer "B.Fab")
			(hide yes)
			(effects
				(font
					(size 1 1)
					(thickness 0.15)
				)
				(justify mirror)
			)
		)
		(property "Dielectric" "X5R"
			(at 0 0 0)
			(layer "B.Fab")
			(hide yes)
			(effects
				(font
					(size 1 1)
					(thickness 0.15)
				)
				(justify mirror)
			)
		)
		(property "License" "Apache-2.0"
			(at 0 0 0)
			(layer "B.Fab")
			(hide yes)
			(effects
				(font
					(size 1 1)
					(thickness 0.15)
				)
				(justify mirror)
			)
		)
		(property "MPN" "GRM155R61H104KE14D"
			(at 0 0 0)
			(layer "B.Fab")
			(hide yes)
			(effects
				(font
					(size 1 1)
					(thickness 0.15)
				)
				(justify mirror)
			)
		)
		(property "Manufacturer" "Murata"
			(at 0 0 0)
			(layer "B.Fab")
			(hide yes)
			(effects
				(font
					(size 1 1)
					(thickness 0.15)
				)
				(justify mirror)
			)
		)
		(property "Val" "100n"
			(at 0 0 0)
			(layer "B.Fab")
			(hide yes)
			(effects
				(font
					(size 1 1)
					(thickness 0.15)
				)
				(justify mirror)
			)
		)
		(property "Voltage" "50V"
			(at 0 0 0)
			(layer "B.Fab")
			(hide yes)
			(effects
				(font
					(size 1 1)
					(thickness 0.15)
				)
				(justify mirror)
			)
		)
		(sheetname "FPGA supply")
		(sheetfile "fpga-supply.kicad_sch")
		(attr smd)
		(fp_rect
			(start -0.925 0.47)
			(end 0.925 -0.47)
			(stroke
				(width 0.05)
				(type default)
			)
			(fill no)
			(layer "B.CrtYd")
		)
		(fp_line
			(start -0.494 -0.248)
			(end -0.494 0.25)
			(stroke
				(width 0.15)
				(type solid)
			)
			(layer "B.Fab")
		)
		(fp_line
			(start -0.494 0.25)
			(end 0.504 0.25)
			(stroke
				(width 0.15)
				(type solid)
			)
			(layer "B.Fab")
		)
		(fp_line
			(start 0.504 -0.248)
			(end -0.494 -0.248)
			(stroke
				(width 0.15)
				(type solid)
			)
			(layer "B.Fab")
		)
		(fp_line
			(start 0.504 0.25)
			(end 0.504 -0.248)
			(stroke
				(width 0.15)
				(type solid)
			)
			(layer "B.Fab")
		)
		(pad "1" smd roundrect
			(at -0.48 0)
			(size 0.59 0.64)
			(layers "B.Cu" "B.Mask" "B.Paste")
			(roundrect_rratio 0.25)
			(net 1 "GND")
			(pintype "passive")
		)
		(pad "2" smd roundrect
			(at 0.48 0)
			(size 0.59 0.64)
			(layers "B.Cu" "B.Mask" "B.Paste")
			(roundrect_rratio 0.25)
			(net 650 "+1V0")
			(pintype "passive")
		)
	)
	(footprint "antmicro-footprints:LED_0603_1608Metric_R"
		(layer "B.Cu")
		(at 268.301 145.35 180)
		(descr "LED SMD 0603 Red")
		(tags "LED SMD 0603 Red")
		(property "Reference" "D13"
			(at 4.101 -0.4 0)
			(layer "B.SilkS")
			(effects
				(font
					(size 0.7 0.7)
					(thickness 0.15)
				)
				(justify left bottom mirror)
			)
		)
		(property "Value" "LED_R_0603_KP-1608EC"
			(at 0 -1.6 0)
			(layer "B.Fab")
			(effects
				(font
					(size 0.7 0.7)
					(thickness 0.15)
				)
				(justify left bottom mirror)
			)
		)
		(property "Description" "LED, Red, SMD, 0603, 30 mA, 2 V, 617 nm"
			(at 0 0 180)
			(layer "F.Fab")
			(hide yes)
			(effects
				(font
					(size 1.27 1.27)
					(thickness 0.15)
				)
			)
		)
		(property "Author" "Antmicro"
			(at 536.602 290.7 0)
			(layer "B.Fab")
			(hide yes)
			(effects
				(font
					(size 1 1)
					(thickness 0.15)
				)
				(justify mirror)
			)
		)
		(property "Color" "Red"
			(at 536.602 290.7 0)
			(layer "B.Fab")
			(hide yes)
			(effects
				(font
					(size 1 1)
					(thickness 0.15)
				)
				(justify mirror)
			)
		)
		(property "License" "Apache-2.0"
			(at 536.602 290.7 0)
			(layer "B.Fab")
			(hide yes)
			(effects
				(font
					(size 1 1)
					(thickness 0.15)
				)
				(justify mirror)
			)
		)
		(property "MPN" "KP-1608EC"
			(at 536.602 290.7 0)
			(layer "B.Fab")
			(hide yes)
			(effects
				(font
					(size 1 1)
					(thickness 0.15)
				)
				(justify mirror)
			)
		)
		(property "Manufacturer" "Kingbright"
			(at 536.602 290.7 0)
			(layer "B.Fab")
			(hide yes)
			(effects
				(font
					(size 1 1)
					(thickness 0.15)
				)
				(justify mirror)
			)
		)
		(property "Public" "False"
			(at 536.602 290.7 0)
			(layer "B.Fab")
			(hide yes)
			(effects
				(font
					(size 1 1)
					(thickness 0.15)
				)
				(justify mirror)
			)
		)
		(sheetname "Power supply")
		(sheetfile "power-supply.kicad_sch")
		(attr smd)
		(fp_line
			(start 0.22 0.35)
			(end -0.22 0.35)
			(stroke
				(width 0.15)
				(type solid)
			)
			(layer "B.SilkS")
		)
		(fp_line
			(start 0.22 -0.35)
			(end -0.22 -0.35)
			(stroke
				(width 0.15)
				(type solid)
			)
			(layer "B.SilkS")
		)
		(fp_line
			(start 0.105328 -0.001008)
			(end 0.24 -0.001)
			(stroke
				(width 0.1)
				(type solid)
			)
			(layer "B.SilkS")
		)
		(fp_line
			(start 0.105328 -0.201008)
			(end 0.105328 0.198992)
			(stroke
				(width 0.1)
				(type solid)
			)
			(layer "B.SilkS")
		)
		(fp_line
			(start 0.105328 -0.201008)
			(end -0.094672 -0.001008)
			(stroke
				(width 0.1)
				(type solid)
			)
			(layer "B.SilkS")
		)
		(fp_line
			(start -0.094672 -0.001008)
			(end 0.105328 0.198992)
			(stroke
				(width 0.1)
				(type solid)
			)
			(layer "B.SilkS")
		)
		(fp_line
			(start -0.094672 -0.001008)
			(end -0.24 -0.001008)
			(stroke
				(width 0.1)
				(type solid)
			)
			(layer "B.SilkS")
		)
		(fp_line
			(start -0.094672 -0.201008)
			(end -0.094672 0.198992)
			(stroke
				(width 0.1)
				(type solid)
			)
			(layer "B.SilkS")
		)
		(fp_line
			(start -1.18 0.319)
			(end -1.18 -0.321)
			(stroke
				(width 0.15)
				(type solid)
			)
			(layer "B.SilkS")
		)
		(fp_rect
			(start 1.25 -0.65)
			(end -1.25 0.65)
			(stroke
				(width 0.05)
				(type solid)
			)
			(fill no)
			(layer "B.CrtYd")
		)
		(fp_line
			(start 0.599 0)
			(end 0.201 0)
			(stroke
				(width 0.15)
				(type solid)
			)
			(layer "B.Fab")
		)
		(fp_line
			(start 0.201 0.202)
			(end -0.101 0)
			(stroke
				(width 0.15)
				(type solid)
			)
			(layer "B.Fab")
		)
		(fp_line
			(start 0.201 0)
			(end 0.201 0.202)
			(stroke
				(width 0.15)
				(type solid)
			)
			(layer "B.Fab")
		)
		(fp_line
			(start 0.201 -0.2)
			(end 0.201 0)
			(stroke
				(width 0.15)
				(type solid)
			)
			(layer "B.Fab")
		)
		(fp_line
			(start -0.101 0)
			(end 0.201 -0.2)
			(stroke
				(width 0.15)
				(type solid)
			)
			(layer "B.Fab")
		)
		(fp_line
			(start -0.199 0.202)
			(end -0.199 -0.1)
			(stroke
				(width 0.15)
				(type solid)
			)
			(layer "B.Fab")
		)
		(fp_line
			(start -0.199 0)
			(end -0.597 0)
			(stroke
				(width 0.15)
				(type solid)
			)
			(layer "B.Fab")
		)
		(fp_line
			(start -0.199 -0.2)
			(end -0.199 -0.1)
			(stroke
				(width 0.15)
				(type solid)
			)
			(layer "B.Fab")
		)
		(fp_rect
			(start 0.848 -0.4)
			(end -0.85 0.402)
			(stroke
				(width 0.15)
				(type solid)
			)
			(fill no)
			(layer "B.Fab")
		)
		(pad "1" smd roundrect
			(at -0.7 0)
			(size 0.8 1)
			(layers "B.Cu" "B.Mask" "B.Paste")
			(roundrect_rratio 0.2)
			(net 1 "GND")
			(pinfunction "C")
			(pintype "passive")
		)
		(pad "2" smd roundrect
			(at 0.7 0)
			(size 0.8 1)
			(layers "B.Cu" "B.Mask" "B.Paste")
			(roundrect_rratio 0.2)
			(net 20 "Net-(D13-A)")
			(pinfunction "A")
			(pintype "passive")
		)
	)
)
